# S9S_MB_2U (Grand Teton) — schematic netlist excerpt (pin names and nets, part order shuffled) for the footprints in the layout excerpt that follows; sources: Cadence DE-HDL packaged netlist, KiCad conversion of 03242023_DA0F0TMBIJ0_F0T_Motherboard_J_brd_V01_OCP.brd

R1660  Q_RES  10K 1% EMPTY  pkg 0402LF  page 220 : A = FM_SLP_SUS_RSM_RST_N ; B = P3V3_AUX
PC493_P1_8  Q_CAP  22UF 16V 20% X6S  pkg C0805  page 288 : A = SW_P12V_PVCCIN_CPU1_FLT ; B = GND
R363  Q_RES  0 5% CHIP  pkg 0402LF  page 278 : A = FM_PVCCD_HV_CPU0_EN ; B = PVCCD_HV_CPU0_EN_R

(kicad_pcb
	(version 20260206)
	(generator "pcbnew")
	(generator_version "10.0")
	(general
		(thickness 1.6)
		(legacy_teardrops no)
	)
	(paper "A4")
	(title_block
		(title "03242023_DA0F0TMBIJ0_F0T_Motherboard_J_brd_V01_OCP.brd")
		(comment 1 "Grand Teton / footprints 5878-5880 of 6105")
	)
	(layers
		(0 "F.Cu" signal "TOP")
		(4 "In1.Cu" signal "GND")
		(6 "In2.Cu" signal "IN1")
		(8 "In3.Cu" signal "GND1")
		(10 "In4.Cu" signal "IN2")
		(12 "In5.Cu" signal "GND2")
		(14 "In6.Cu" signal "IN3")
		(16 "In7.Cu" signal "GND3")
		(18 "In8.Cu" signal "VCC")
		(20 "In9.Cu" signal "VCC1")
		(22 "In10.Cu" signal "GND4")
		(24 "In11.Cu" signal "IN4")
		(26 "In12.Cu" signal "GND5")
		(28 "In13.Cu" signal "IN5")
		(30 "In14.Cu" signal "GND6")
		(32 "In15.Cu" signal "IN6")
		(34 "In16.Cu" signal "GND7")
		(2 "B.Cu" signal "BOTTOM")
		(9 "F.Adhes" user "F.Adhesive")
		(11 "B.Adhes" user "B.Adhesive")
		(13 "F.Paste" user "Package Geometry/Pastemask Top")
		(15 "B.Paste" user "Package Geometry/Pastemask Bottom")
		(5 "F.SilkS" user "Ref Des/Silkscreen Top")
		(7 "B.SilkS" user "Ref Des/Silkscreen Bottom")
		(1 "F.Mask" user "Board Geometry/Soldermask Top")
		(3 "B.Mask" user "Board Geometry/Soldermask Bottom")
		(17 "Dwgs.User" user "User.Drawings")
		(19 "Cmts.User" user "User.Comments")
		(21 "Eco1.User" user "User.Eco1")
		(23 "Eco2.User" user "User.Eco2")
		(25 "Edge.Cuts" user "Board Geometry/Outline")
		(27 "Margin" user)
		(31 "F.CrtYd" user "Package Geometry/Place Bound Top")
		(29 "B.CrtYd" user "Package Geometry/Place Bound Bottom")
		(35 "F.Fab" user "Ref Des/Assembly Top")
		(33 "B.Fab" user "Ref Des/Assembly Bottom")
	)
	(footprint ""
		(layer "B.Cu")
		(at 141.057122 -342.936576 90)
		(property "Reference" "PC493_P1_8"
			(at 0 0 90)
			(layer "B.SilkS")
			(hide yes)
			(effects
				(font
					(size 1.27 1.27)
				)
				(justify mirror)
			)
		)
		(property "Value" ""
			(at 0 0 90)
			(layer "B.Fab")
			(effects
				(font
					(size 1.27 1.27)
				)
				(justify mirror)
			)
		)
		(duplicate_pad_numbers_are_jumpers no)
		(fp_line
			(start 1.524 -0.762)
			(end -1.524 -0.762)
			(stroke
				(width 0.1524)
				(type default)
			)
			(layer "B.SilkS")
		)
		(fp_line
			(start -1.524 -0.762)
			(end -1.524 0.762)
			(stroke
				(width 0.1524)
				(type default)
			)
			(layer "B.SilkS")
		)
		(fp_line
			(start 1.524 0.762)
			(end 1.524 -0.762)
			(stroke
				(width 0.1524)
				(type default)
			)
			(layer "B.SilkS")
		)
		(fp_line
			(start -1.524 0.762)
			(end 1.524 0.762)
			(stroke
				(width 0.1524)
				(type default)
			)
			(layer "B.SilkS")
		)
		(fp_line
			(start 1.1049 -0.724916)
			(end 1.1049 0.724916)
			(stroke
				(width 0.1)
				(type default)
			)
			(layer "B.Fab")
		)
		(fp_line
			(start -1.1049 -0.724916)
			(end 1.1049 -0.724916)
			(stroke
				(width 0.1)
				(type default)
			)
			(layer "B.Fab")
		)
		(fp_line
			(start 1.1049 0.724916)
			(end -1.1049 0.724916)
			(stroke
				(width 0.1)
				(type default)
			)
			(layer "B.Fab")
		)
		(fp_line
			(start -1.1049 0.724916)
			(end -1.1049 -0.724916)
			(stroke
				(width 0.1)
				(type default)
			)
			(layer "B.Fab")
		)
		(pad "1" smd rect
			(at 0.889 0 90)
			(size 1.016 1.27)
			(layers "B.Cu" "B.Mask" "B.Paste")
			(net "SW_P12V_PVCCIN_CPU1_FLT")
		)
		(pad "2" smd rect
			(at -0.889 0 90)
			(size 1.016 1.27)
			(layers "B.Cu" "B.Mask" "B.Paste")
			(net "GND")
		)
	)
	(footprint ""
		(layer "B.Cu")
		(at 164.64788 -111.470948)
		(property "Reference" "R1660"
			(at 0 0 0)
			(layer "B.SilkS")
			(hide yes)
			(effects
				(font
					(size 1.27 1.27)
				)
				(justify mirror)
			)
		)
		(property "Value" ""
			(at 0 0 0)
			(layer "B.Fab")
			(effects
				(font
					(size 1.27 1.27)
				)
				(justify mirror)
			)
		)
		(duplicate_pad_numbers_are_jumpers no)
		(fp_line
			(start -0.7874 -0.4064)
			(end -0.7874 0.4064)
			(stroke
				(width 0.1524)
				(type default)
			)
			(layer "B.SilkS")
		)
		(fp_line
			(start -0.7874 0.4064)
			(end 0.7874 0.4064)
			(stroke
				(width 0.1524)
				(type default)
			)
			(layer "B.SilkS")
		)
		(fp_line
			(start 0.7874 -0.4064)
			(end -0.7874 -0.4064)
			(stroke
				(width 0.1524)
				(type default)
			)
			(layer "B.SilkS")
		)
		(fp_line
			(start 0.7874 0.4064)
			(end 0.7874 -0.4064)
			(stroke
				(width 0.1524)
				(type default)
			)
			(layer "B.SilkS")
		)
		(fp_line
			(start -0.67945 -0.3048)
			(end -0.67945 0.3048)
			(stroke
				(width 0.1)
				(type default)
			)
			(layer "B.Fab")
		)
		(fp_line
			(start -0.67945 0.3048)
			(end -0.120396 0.3048)
			(stroke
				(width 0.1)
				(type default)
			)
			(layer "B.Fab")
		)
		(fp_line
			(start -0.12065 -0.3048)
			(end -0.67945 -0.3048)
			(stroke
				(width 0.1)
				(type default)
			)
			(layer "B.Fab")
		)
		(fp_line
			(start -0.12065 -0.2794)
			(end -0.12065 -0.3048)
			(stroke
				(width 0.1)
				(type default)
			)
			(layer "B.Fab")
		)
		(fp_line
			(start -0.120396 0.2794)
			(end 0.12065 0.2794)
			(stroke
				(width 0.1)
				(type default)
			)
			(layer "B.Fab")
		)
		(fp_line
			(start -0.120396 0.3048)
			(end -0.120396 0.2794)
			(stroke
				(width 0.1)
				(type default)
			)
			(layer "B.Fab")
		)
		(fp_line
			(start 0.12065 -0.305054)
			(end 0.12065 -0.2794)
			(stroke
				(width 0.1)
				(type default)
			)
			(layer "B.Fab")
		)
		(fp_line
			(start 0.12065 -0.2794)
			(end -0.12065 -0.2794)
			(stroke
				(width 0.1)
				(type default)
			)
			(layer "B.Fab")
		)
		(fp_line
			(start 0.12065 0.2794)
			(end 0.12065 0.3048)
			(stroke
				(width 0.1)
				(type default)
			)
			(layer "B.Fab")
		)
		(fp_line
			(start 0.12065 0.3048)
			(end 0.67945 0.3048)
			(stroke
				(width 0.1)
				(type default)
			)
			(layer "B.Fab")
		)
		(fp_line
			(start 0.67945 -0.305054)
			(end 0.12065 -0.305054)
			(stroke
				(width 0.1)
				(type default)
			)
			(layer "B.Fab")
		)
		(fp_line
			(start 0.67945 0.3048)
			(end 0.67945 -0.305054)
			(stroke
				(width 0.1)
				(type default)
			)
			(layer "B.Fab")
		)
		(pad "1" smd circle
			(at 0.40005 0 180)
			(size 0 0)
			(layers "B.Cu" "B.Mask" "B.Paste")
			(net "FM_SLP_SUS_RSM_RST_N")
		)
		(pad "2" smd circle
			(at -0.40005 0 180)
			(size 0 0)
			(layers "B.Cu" "B.Mask" "B.Paste")
			(net "P3V3_AUX")
		)
	)
	(footprint ""
		(layer "B.Cu")
		(at 436.971694 -121.730008)
		(property "Reference" "R363"
			(at 0 0 0)
			(layer "B.SilkS")
			(hide yes)
			(effects
				(font
					(size 1.27 1.27)
				)
				(justify mirror)
			)
		)
		(property "Value" ""
			(at 0 0 0)
			(layer "B.Fab")
			(effects
				(font
					(size 1.27 1.27)
				)
				(justify mirror)
			)
		)
		(duplicate_pad_numbers_are_jumpers no)
		(fp_line
			(start -0.7874 -0.4064)
			(end -0.7874 0.4064)
			(stroke
				(width 0.1524)
				(type default)
			)
			(layer "B.SilkS")
		)
		(fp_line
			(start -0.7874 0.4064)
			(end 0.7874 0.4064)
			(stroke
				(width 0.1524)
				(type default)
			)
			(layer "B.SilkS")
		)
		(fp_line
			(start 0.7874 -0.4064)
			(end -0.7874 -0.4064)
			(stroke
				(width 0.1524)
				(type default)
			)
			(layer "B.SilkS")
		)
		(fp_line
			(start 0.7874 0.4064)
			(end 0.7874 -0.4064)
			(stroke
				(width 0.1524)
				(type default)
			)
			(layer "B.SilkS")
		)
		(fp_line
			(start -0.67945 -0.3048)
			(end -0.67945 0.3048)
			(stroke
				(width 0.1)
				(type default)
			)
			(layer "B.Fab")
		)
		(fp_line
			(start -0.67945 0.3048)
			(end -0.120396 0.3048)
			(stroke
				(width 0.1)
				(type default)
			)
			(layer "B.Fab")
		)
		(fp_line
			(start -0.12065 -0.3048)
			(end -0.67945 -0.3048)
			(stroke
				(width 0.1)
				(type default)
			)
			(layer "B.Fab")
		)
		(fp_line
			(start -0.12065 -0.2794)
			(end -0.12065 -0.3048)
			(stroke
				(width 0.1)
				(type default)
			)
			(layer "B.Fab")
		)
		(fp_line
			(start -0.120396 0.2794)
			(end 0.12065 0.2794)
			(stroke
				(width 0.1)
				(type default)
			)
			(layer "B.Fab")
		)
		(fp_line
			(start -0.120396 0.3048)
			(end -0.120396 0.2794)
			(stroke
				(width 0.1)
				(type default)
			)
			(layer "B.Fab")
		)
		(fp_line
			(start 0.12065 -0.305054)
			(end 0.12065 -0.2794)
			(stroke
				(width 0.1)
				(type default)
			)
			(layer "B.Fab")
		)
		(fp_line
			(start 0.12065 -0.2794)
			(end -0.12065 -0.2794)
			(stroke
				(width 0.1)
				(type default)
			)
			(layer "B.Fab")
		)
		(fp_line
			(start 0.12065 0.2794)
			(end 0.12065 0.3048)
			(stroke
				(width 0.1)
				(type default)
			)
			(layer "B.Fab")
		)
		(fp_line
			(start 0.12065 0.3048)
			(end 0.67945 0.3048)
			(stroke
				(width 0.1)
				(type default)
			)
			(layer "B.Fab")
		)
		(fp_line
			(start 0.67945 -0.305054)
			(end 0.12065 -0.305054)
			(stroke
				(width 0.1)
				(type default)
			)
			(layer "B.Fab")
		)
		(fp_line
			(start 0.67945 0.3048)
			(end 0.67945 -0.305054)
			(stroke
				(width 0.1)
				(type default)
			)
			(layer "B.Fab")
		)
		(pad "1" smd circle
			(at 0.40005 0 180)
			(size 0 0)
			(layers "B.Cu" "B.Mask" "B.Paste")
			(net "FM_PVCCD_HV_CPU0_EN")
		)
		(pad "2" smd circle
			(at -0.40005 0 180)
			(size 0 0)
			(layers "B.Cu" "B.Mask" "B.Paste")
			(net "PVCCD_HV_CPU0_EN_R")
		)
	)
)
